(kicad_pcb
	(version 20260206)
	(generator "pcbnew")
	(generator_version "10.0")
	(general
		(thickness 1.6)
		(legacy_teardrops no)
	)
	(paper "A4")
	(title_block
		(title "04192023_DAF0TMB3IC0_F0TG_MB_C_brd_V02_OCP.brd")
		(comment 1 "Grand Teton / footprints 803-810 of 8354")
	)
	(layers
		(0 "F.Cu" signal "TOP")
		(4 "In1.Cu" signal "GND")
		(6 "In2.Cu" signal "IN1")
		(8 "In3.Cu" signal "GND1")
		(10 "In4.Cu" signal "IN2")
		(12 "In5.Cu" signal "GND2")
		(14 "In6.Cu" signal "IN3")
		(16 "In7.Cu" signal "GND3")
		(18 "In8.Cu" signal "VCC")
		(20 "In9.Cu" signal "VCC1")
		(22 "In10.Cu" signal "GND4")
		(24 "In11.Cu" signal "IN4")
		(26 "In12.Cu" signal "GND5")
		(28 "In13.Cu" signal "IN5")
		(30 "In14.Cu" signal "GND6")
		(32 "In15.Cu" signal "IN6")
		(34 "In16.Cu" signal "GND7")
		(2 "B.Cu" signal "BOTTOM")
		(9 "F.Adhes" user "F.Adhesive")
		(11 "B.Adhes" user "B.Adhesive")
		(13 "F.Paste" user "Package Geometry/Pastemask Top")
		(15 "B.Paste" user "Package Geometry/Pastemask Bottom")
		(5 "F.SilkS" user "Ref Des/Silkscreen Top")
		(7 "B.SilkS" user "Ref Des/Silkscreen Bottom")
		(1 "F.Mask" user "Board Geometry/Soldermask Top")
		(3 "B.Mask" user "Board Geometry/Soldermask Bottom")
		(17 "Dwgs.User" user "User.Drawings")
		(19 "Cmts.User" user "User.Comments")
		(21 "Eco1.User" user "User.Eco1")
		(23 "Eco2.User" user "User.Eco2")
		(25 "Edge.Cuts" user "Board Geometry/Outline")
		(27 "Margin" user)
		(31 "F.CrtYd" user "Package Geometry/Place Bound Top")
		(29 "B.CrtYd" user "Package Geometry/Place Bound Bottom")
		(35 "F.Fab" user "Ref Des/Assembly Top")
		(33 "B.Fab" user "Ref Des/Assembly Bottom")
	)
	(footprint ""
		(layer "F.Cu")
		(at 61.90488 -18.252948)
		(property "Reference" "R3217"
			(at 0 0 0)
			(layer "F.SilkS")
			(hide yes)
			(effects
				(font
					(size 1.27 1.27)
				)
			)
		)
		(property "Value" ""
			(at 0 0 0)
			(layer "F.Fab")
			(effects
				(font
					(size 1.27 1.27)
				)
			)
		)
		(duplicate_pad_numbers_are_jumpers no)
		(fp_line
			(start -0.7874 -0.4064)
			(end 0.7874 -0.4064)
			(stroke
				(width 0.1524)
				(type default)
			)
			(layer "F.SilkS")
		)
		(fp_line
			(start -0.7874 0.4064)
			(end -0.7874 -0.4064)
			(stroke
				(width 0.1524)
				(type default)
			)
			(layer "F.SilkS")
		)
		(fp_line
			(start 0.7874 -0.4064)
			(end 0.7874 0.4064)
			(stroke
				(width 0.1524)
				(type default)
			)
			(layer "F.SilkS")
		)
		(fp_line
			(start 0.7874 0.4064)
			(end -0.7874 0.4064)
			(stroke
				(width 0.1524)
				(type default)
			)
			(layer "F.SilkS")
		)
		(fp_line
			(start -0.67945 -0.305054)
			(end -0.12065 -0.305054)
			(stroke
				(width 0.1)
				(type default)
			)
			(layer "F.Fab")
		)
		(fp_line
			(start -0.67945 0.3048)
			(end -0.67945 -0.305054)
			(stroke
				(width 0.1)
				(type default)
			)
			(layer "F.Fab")
		)
		(fp_line
			(start -0.12065 -0.305054)
			(end -0.12065 -0.2794)
			(stroke
				(width 0.1)
				(type default)
			)
			(layer "F.Fab")
		)
		(fp_line
			(start -0.12065 -0.2794)
			(end 0.12065 -0.2794)
			(stroke
				(width 0.1)
				(type default)
			)
			(layer "F.Fab")
		)
		(fp_line
			(start -0.12065 0.2794)
			(end -0.12065 0.3048)
			(stroke
				(width 0.1)
				(type default)
			)
			(layer "F.Fab")
		)
		(fp_line
			(start -0.12065 0.3048)
			(end -0.67945 0.3048)
			(stroke
				(width 0.1)
				(type default)
			)
			(layer "F.Fab")
		)
		(fp_line
			(start 0.120396 0.2794)
			(end -0.12065 0.2794)
			(stroke
				(width 0.1)
				(type default)
			)
			(layer "F.Fab")
		)
		(fp_line
			(start 0.120396 0.3048)
			(end 0.120396 0.2794)
			(stroke
				(width 0.1)
				(type default)
			)
			(layer "F.Fab")
		)
		(fp_line
			(start 0.12065 -0.3048)
			(end 0.67945 -0.3048)
			(stroke
				(width 0.1)
				(type default)
			)
			(layer "F.Fab")
		)
		(fp_line
			(start 0.12065 -0.2794)
			(end 0.12065 -0.3048)
			(stroke
				(width 0.1)
				(type default)
			)
			(layer "F.Fab")
		)
		(fp_line
			(start 0.67945 -0.3048)
			(end 0.67945 0.3048)
			(stroke
				(width 0.1)
				(type default)
			)
			(layer "F.Fab")
		)
		(fp_line
			(start 0.67945 0.3048)
			(end 0.120396 0.3048)
			(stroke
				(width 0.1)
				(type default)
			)
			(layer "F.Fab")
		)
		(pad "1" smd circle
			(at -0.40005 0)
			(size 0 0)
			(layers "F.Cu" "F.Mask" "F.Paste")
			(net "OCP_V3_2_ISO_BIF2_EN")
		)
		(pad "2" smd circle
			(at 0.40005 0)
			(size 0 0)
			(layers "F.Cu" "F.Mask" "F.Paste")
			(net "GND")
		)
	)
	(footprint ""
		(layer "F.Cu")
		(at 143.350488 -394.903452 90)
		(property "Reference" "R860"
			(at 0 0 90)
			(layer "F.SilkS")
			(hide yes)
			(effects
				(font
					(size 1.27 1.27)
				)
			)
		)
		(property "Value" ""
			(at 0 0 90)
			(layer "F.Fab")
			(effects
				(font
					(size 1.27 1.27)
				)
			)
		)
		(duplicate_pad_numbers_are_jumpers no)
		(fp_line
			(start 0.32512 -0.175006)
			(end 0.32512 0.175006)
			(stroke
				(width 0.1)
				(type default)
			)
			(layer "F.Fab")
		)
		(fp_line
			(start -0.32512 -0.175006)
			(end 0.32512 -0.175006)
			(stroke
				(width 0.1)
				(type default)
			)
			(layer "F.Fab")
		)
		(fp_line
			(start 0.32512 0.175006)
			(end -0.32512 0.175006)
			(stroke
				(width 0.1)
				(type default)
			)
			(layer "F.Fab")
		)
		(fp_line
			(start -0.32512 0.175006)
			(end -0.32512 -0.175006)
			(stroke
				(width 0.1)
				(type default)
			)
			(layer "F.Fab")
		)
		(pad "1" smd rect
			(at -0.2667 0 90)
			(size 0.3048 0.381)
			(layers "F.Cu" "F.Mask" "F.Paste")
			(net "RST_RT_CPU1_P2_RESET_N")
		)
		(pad "2" smd rect
			(at 0.2667 0 270)
			(size 0.3048 0.381)
			(layers "F.Cu" "F.Mask" "F.Paste")
			(net "RST_RT_CPU1_P2_RESET_R_N")
		)
	)
	(footprint ""
		(layer "F.Cu")
		(at 424.755564 -16.100298 90)
		(property "Reference" "C1573"
			(at 0 0 90)
			(layer "F.SilkS")
			(hide yes)
			(effects
				(font
					(size 1.27 1.27)
				)
			)
		)
		(property "Value" ""
			(at 0 0 90)
			(layer "F.Fab")
			(effects
				(font
					(size 1.27 1.27)
				)
			)
		)
		(duplicate_pad_numbers_are_jumpers no)
		(fp_line
			(start 0.299974 -0.150114)
			(end 0.299974 0.150114)
			(stroke
				(width 0.1)
				(type default)
			)
			(layer "F.Fab")
		)
		(fp_line
			(start -0.299974 -0.150114)
			(end 0.299974 -0.150114)
			(stroke
				(width 0.1)
				(type default)
			)
			(layer "F.Fab")
		)
		(fp_line
			(start 0.299974 0.150114)
			(end -0.299974 0.150114)
			(stroke
				(width 0.1)
				(type default)
			)
			(layer "F.Fab")
		)
		(fp_line
			(start -0.299974 0.150114)
			(end -0.299974 -0.150114)
			(stroke
				(width 0.1)
				(type default)
			)
			(layer "F.Fab")
		)
		(pad "1" smd rect
			(at -0.2667 0 90)
			(size 0.3048 0.381)
			(layers "F.Cu" "F.Mask" "F.Paste")
			(net "P5E_CPU0_G3_TX_C_DP<3>")
		)
		(pad "2" smd rect
			(at 0.2667 0 90)
			(size 0.3048 0.381)
			(layers "F.Cu" "F.Mask" "F.Paste")
			(net "P5E_CPU0_G3_TX_DP<3>")
		)
	)
	(footprint ""
		(layer "F.Cu")
		(at 106.934 -13.909548 180)
		(property "Reference" "R4208"
			(at 0 0 180)
			(layer "F.SilkS")
			(hide yes)
			(effects
				(font
					(size 1.27 1.27)
				)
			)
		)
		(property "Value" ""
			(at 0 0 180)
			(layer "F.Fab")
			(effects
				(font
					(size 1.27 1.27)
				)
			)
		)
		(duplicate_pad_numbers_are_jumpers no)
		(fp_line
			(start 0.7874 0.4064)
			(end -0.7874 0.4064)
			(stroke
				(width 0.1524)
				(type default)
			)
			(layer "F.SilkS")
		)
		(fp_line
			(start 0.7874 -0.4064)
			(end 0.7874 0.4064)
			(stroke
				(width 0.1524)
				(type default)
			)
			(layer "F.SilkS")
		)
		(fp_line
			(start -0.7874 0.4064)
			(end -0.7874 -0.4064)
			(stroke
				(width 0.1524)
				(type default)
			)
			(layer "F.SilkS")
		)
		(fp_line
			(start -0.7874 -0.4064)
			(end 0.7874 -0.4064)
			(stroke
				(width 0.1524)
				(type default)
			)
			(layer "F.SilkS")
		)
		(fp_line
			(start 0.67945 0.3048)
			(end 0.120396 0.3048)
			(stroke
				(width 0.1)
				(type default)
			)
			(layer "F.Fab")
		)
		(fp_line
			(start 0.67945 -0.3048)
			(end 0.67945 0.3048)
			(stroke
				(width 0.1)
				(type default)
			)
			(layer "F.Fab")
		)
		(fp_line
			(start 0.12065 -0.2794)
			(end 0.12065 -0.3048)
			(stroke
				(width 0.1)
				(type default)
			)
			(layer "F.Fab")
		)
		(fp_line
			(start 0.12065 -0.3048)
			(end 0.67945 -0.3048)
			(stroke
				(width 0.1)
				(type default)
			)
			(layer "F.Fab")
		)
		(fp_line
			(start 0.120396 0.3048)
			(end 0.120396 0.2794)
			(stroke
				(width 0.1)
				(type default)
			)
			(layer "F.Fab")
		)
		(fp_line
			(start 0.120396 0.2794)
			(end -0.12065 0.2794)
			(stroke
				(width 0.1)
				(type default)
			)
			(layer "F.Fab")
		)
		(fp_line
			(start -0.12065 0.3048)
			(end -0.67945 0.3048)
			(stroke
				(width 0.1)
				(type default)
			)
			(layer "F.Fab")
		)
		(fp_line
			(start -0.12065 0.2794)
			(end -0.12065 0.3048)
			(stroke
				(width 0.1)
				(type default)
			)
			(layer "F.Fab")
		)
		(fp_line
			(start -0.12065 -0.2794)
			(end 0.12065 -0.2794)
			(stroke
				(width 0.1)
				(type default)
			)
			(layer "F.Fab")
		)
		(fp_line
			(start -0.12065 -0.305054)
			(end -0.12065 -0.2794)
			(stroke
				(width 0.1)
				(type default)
			)
			(layer "F.Fab")
		)
		(fp_line
			(start -0.67945 0.3048)
			(end -0.67945 -0.305054)
			(stroke
				(width 0.1)
				(type default)
			)
			(layer "F.Fab")
		)
		(fp_line
			(start -0.67945 -0.305054)
			(end -0.12065 -0.305054)
			(stroke
				(width 0.1)
				(type default)
			)
			(layer "F.Fab")
		)
		(pad "1" smd circle
			(at -0.40005 0 180)
			(size 0 0)
			(layers "F.Cu" "F.Mask" "F.Paste")
			(net "P3V3_AUX")
		)
		(pad "2" smd circle
			(at 0.40005 0 180)
			(size 0 0)
			(layers "F.Cu" "F.Mask" "F.Paste")
			(net "FM_THERMAL_ALERT_N")
		)
	)
	(footprint ""
		(layer "F.Cu")
		(at 331.337666 -416.899344 -90)
		(property "Reference" "C6520"
			(at 0 0 270)
			(layer "F.SilkS")
			(hide yes)
			(effects
				(font
					(size 1.27 1.27)
				)
			)
		)
		(property "Value" ""
			(at 0 0 270)
			(layer "F.Fab")
			(effects
				(font
					(size 1.27 1.27)
				)
			)
		)
		(duplicate_pad_numbers_are_jumpers no)
		(fp_line
			(start -0.299974 0.150114)
			(end -0.299974 -0.150114)
			(stroke
				(width 0.1)
				(type default)
			)
			(layer "F.Fab")
		)
		(fp_line
			(start 0.299974 0.150114)
			(end -0.299974 0.150114)
			(stroke
				(width 0.1)
				(type default)
			)
			(layer "F.Fab")
		)
		(fp_line
			(start -0.299974 -0.150114)
			(end 0.299974 -0.150114)
			(stroke
				(width 0.1)
				(type default)
			)
			(layer "F.Fab")
		)
		(fp_line
			(start 0.299974 -0.150114)
			(end 0.299974 0.150114)
			(stroke
				(width 0.1)
				(type default)
			)
			(layer "F.Fab")
		)
		(pad "1" smd rect
			(at -0.2667 0 270)
			(size 0.3048 0.381)
			(layers "F.Cu" "F.Mask" "F.Paste")
			(net "P5E_CPU0_P0_TX_BUF_C_DN<9>")
		)
		(pad "2" smd rect
			(at 0.2667 0 270)
			(size 0.3048 0.381)
			(layers "F.Cu" "F.Mask" "F.Paste")
			(net "P5E_CPU0_P0_TX_BUF_DN<9>")
		)
	)
	(footprint ""
		(layer "F.Cu")
		(at 305.177698 -118.179088)
		(property "Reference" "R717"
			(at 0 0 0)
			(layer "F.SilkS")
			(hide yes)
			(effects
				(font
					(size 1.27 1.27)
				)
			)
		)
		(property "Value" ""
			(at 0 0 0)
			(layer "F.Fab")
			(effects
				(font
					(size 1.27 1.27)
				)
			)
		)
		(duplicate_pad_numbers_are_jumpers no)
		(fp_line
			(start -0.7874 -0.4064)
			(end 0.7874 -0.4064)
			(stroke
				(width 0.1524)
				(type default)
			)
			(layer "F.SilkS")
		)
		(fp_line
			(start -0.7874 0.4064)
			(end -0.7874 -0.4064)
			(stroke
				(width 0.1524)
				(type default)
			)
			(layer "F.SilkS")
		)
		(fp_line
			(start 0.7874 -0.4064)
			(end 0.7874 0.4064)
			(stroke
				(width 0.1524)
				(type default)
			)
			(layer "F.SilkS")
		)
		(fp_line
			(start 0.7874 0.4064)
			(end -0.7874 0.4064)
			(stroke
				(width 0.1524)
				(type default)
			)
			(layer "F.SilkS")
		)
		(fp_line
			(start -0.67945 -0.305054)
			(end -0.12065 -0.305054)
			(stroke
				(width 0.1)
				(type default)
			)
			(layer "F.Fab")
		)
		(fp_line
			(start -0.67945 0.3048)
			(end -0.67945 -0.305054)
			(stroke
				(width 0.1)
				(type default)
			)
			(layer "F.Fab")
		)
		(fp_line
			(start -0.12065 -0.305054)
			(end -0.12065 -0.2794)
			(stroke
				(width 0.1)
				(type default)
			)
			(layer "F.Fab")
		)
		(fp_line
			(start -0.12065 -0.2794)
			(end 0.12065 -0.2794)
			(stroke
				(width 0.1)
				(type default)
			)
			(layer "F.Fab")
		)
		(fp_line
			(start -0.12065 0.2794)
			(end -0.12065 0.3048)
			(stroke
				(width 0.1)
				(type default)
			)
			(layer "F.Fab")
		)
		(fp_line
			(start -0.12065 0.3048)
			(end -0.67945 0.3048)
			(stroke
				(width 0.1)
				(type default)
			)
			(layer "F.Fab")
		)
		(fp_line
			(start 0.120396 0.2794)
			(end -0.12065 0.2794)
			(stroke
				(width 0.1)
				(type default)
			)
			(layer "F.Fab")
		)
		(fp_line
			(start 0.120396 0.3048)
			(end 0.120396 0.2794)
			(stroke
				(width 0.1)
				(type default)
			)
			(layer "F.Fab")
		)
		(fp_line
			(start 0.12065 -0.3048)
			(end 0.67945 -0.3048)
			(stroke
				(width 0.1)
				(type default)
			)
			(layer "F.Fab")
		)
		(fp_line
			(start 0.12065 -0.2794)
			(end 0.12065 -0.3048)
			(stroke
				(width 0.1)
				(type default)
			)
			(layer "F.Fab")
		)
		(fp_line
			(start 0.67945 -0.3048)
			(end 0.67945 0.3048)
			(stroke
				(width 0.1)
				(type default)
			)
			(layer "F.Fab")
		)
		(fp_line
			(start 0.67945 0.3048)
			(end 0.120396 0.3048)
			(stroke
				(width 0.1)
				(type default)
			)
			(layer "F.Fab")
		)
		(pad "1" smd circle
			(at -0.40005 0)
			(size 0 0)
			(layers "F.Cu" "F.Mask" "F.Paste")
			(net "P3V3_AUX")
		)
		(pad "2" smd circle
			(at 0.40005 0)
			(size 0 0)
			(layers "F.Cu" "F.Mask" "F.Paste")
			(net "MB_FRU_ADDR1")
		)
	)
	(footprint ""
		(layer "F.Cu")
		(at 200.952608 -113.625376 180)
		(property "Reference" "R1314"
			(at 0 0 180)
			(layer "F.SilkS")
			(hide yes)
			(effects
				(font
					(size 1.27 1.27)
				)
			)
		)
		(property "Value" ""
			(at 0 0 180)
			(layer "F.Fab")
			(effects
				(font
					(size 1.27 1.27)
				)
			)
		)
		(duplicate_pad_numbers_are_jumpers no)
		(fp_line
			(start 0.7874 0.4064)
			(end -0.7874 0.4064)
			(stroke
				(width 0.1524)
				(type default)
			)
			(layer "F.SilkS")
		)
		(fp_line
			(start 0.7874 -0.4064)
			(end 0.7874 0.4064)
			(stroke
				(width 0.1524)
				(type default)
			)
			(layer "F.SilkS")
		)
		(fp_line
			(start -0.7874 0.4064)
			(end -0.7874 -0.4064)
			(stroke
				(width 0.1524)
				(type default)
			)
			(layer "F.SilkS")
		)
		(fp_line
			(start -0.7874 -0.4064)
			(end 0.7874 -0.4064)
			(stroke
				(width 0.1524)
				(type default)
			)
			(layer "F.SilkS")
		)
		(fp_line
			(start 0.67945 0.3048)
			(end 0.120396 0.3048)
			(stroke
				(width 0.1)
				(type default)
			)
			(layer "F.Fab")
		)
		(fp_line
			(start 0.67945 -0.3048)
			(end 0.67945 0.3048)
			(stroke
				(width 0.1)
				(type default)
			)
			(layer "F.Fab")
		)
		(fp_line
			(start 0.12065 -0.2794)
			(end 0.12065 -0.3048)
			(stroke
				(width 0.1)
				(type default)
			)
			(layer "F.Fab")
		)
		(fp_line
			(start 0.12065 -0.3048)
			(end 0.67945 -0.3048)
			(stroke
				(width 0.1)
				(type default)
			)
			(layer "F.Fab")
		)
		(fp_line
			(start 0.120396 0.3048)
			(end 0.120396 0.2794)
			(stroke
				(width 0.1)
				(type default)
			)
			(layer "F.Fab")
		)
		(fp_line
			(start 0.120396 0.2794)
			(end -0.12065 0.2794)
			(stroke
				(width 0.1)
				(type default)
			)
			(layer "F.Fab")
		)
		(fp_line
			(start -0.12065 0.3048)
			(end -0.67945 0.3048)
			(stroke
				(width 0.1)
				(type default)
			)
			(layer "F.Fab")
		)
		(fp_line
			(start -0.12065 0.2794)
			(end -0.12065 0.3048)
			(stroke
				(width 0.1)
				(type default)
			)
			(layer "F.Fab")
		)
		(fp_line
			(start -0.12065 -0.2794)
			(end 0.12065 -0.2794)
			(stroke
				(width 0.1)
				(type default)
			)
			(layer "F.Fab")
		)
		(fp_line
			(start -0.12065 -0.305054)
			(end -0.12065 -0.2794)
			(stroke
				(width 0.1)
				(type default)
			)
			(layer "F.Fab")
		)
		(fp_line
			(start -0.67945 0.3048)
			(end -0.67945 -0.305054)
			(stroke
				(width 0.1)
				(type default)
			)
			(layer "F.Fab")
		)
		(fp_line
			(start -0.67945 -0.305054)
			(end -0.12065 -0.305054)
			(stroke
				(width 0.1)
				(type default)
			)
			(layer "F.Fab")
		)
		(pad "1" smd circle
			(at -0.40005 0 180)
			(size 0 0)
			(layers "F.Cu" "F.Mask" "F.Paste")
			(net "E1S_0_P12V_EN")
		)
		(pad "2" smd circle
			(at 0.40005 0 180)
			(size 0 0)
			(layers "F.Cu" "F.Mask" "F.Paste")
			(net "P3V3_AUX")
		)
	)
	(footprint ""
		(layer "F.Cu")
		(at 72.466454 -148.635212 179.946)
		(property "Reference" "PR147"
			(at 0 0 179.946)
			(layer "F.SilkS")
			(hide yes)
			(effects
				(font
					(size 1.27 1.27)
				)
			)
		)
		(property "Value" ""
			(at 0 0 179.946)
			(layer "F.Fab")
			(effects
				(font
					(size 1.27 1.27)
				)
			)
		)
		(duplicate_pad_numbers_are_jumpers no)
		(fp_line
			(start 0.787525 -0.40638)
			(end 0.787275 0.40642)
			(stroke
				(width 0.1524)
				(type default)
			)
			(layer "F.SilkS")
		)
		(fp_line
			(start 0.787275 0.40642)
			(end -0.787525 0.40638)
			(stroke
				(width 0.1524)
				(type default)
			)
			(layer "F.SilkS")
		)
		(fp_line
			(start -0.787275 -0.40642)
			(end 0.787525 -0.40638)
			(stroke
				(width 0.1524)
				(type default)
			)
			(layer "F.SilkS")
		)
		(fp_line
			(start -0.787525 0.40638)
			(end -0.787275 -0.40642)
			(stroke
				(width 0.1524)
				(type default)
			)
			(layer "F.SilkS")
		)
		(fp_line
			(start 0.679417 -0.304678)
			(end 0.679484 0.304922)
			(stroke
				(width 0.1)
				(type default)
			)
			(layer "F.Fab")
		)
		(fp_line
			(start 0.679484 0.304922)
			(end 0.120429 0.304687)
			(stroke
				(width 0.1)
				(type default)
			)
			(layer "F.Fab")
		)
		(fp_line
			(start 0.120641 -0.279514)
			(end 0.120617 -0.304914)
			(stroke
				(width 0.1)
				(type default)
			)
			(layer "F.Fab")
		)
		(fp_line
			(start 0.120617 -0.304914)
			(end 0.679417 -0.304678)
			(stroke
				(width 0.1)
				(type default)
			)
			(layer "F.Fab")
		)
		(fp_line
			(start 0.120429 0.304687)
			(end 0.120405 0.279287)
			(stroke
				(width 0.1)
				(type default)
			)
			(layer "F.Fab")
		)
		(fp_line
			(start 0.120405 0.279287)
			(end -0.120641 0.279514)
			(stroke
				(width 0.1)
				(type default)
			)
			(layer "F.Fab")
		)
		(fp_line
			(start -0.120659 -0.279286)
			(end 0.120641 -0.279514)
			(stroke
				(width 0.1)
				(type default)
			)
			(layer "F.Fab")
		)
		(fp_line
			(start -0.120683 -0.30494)
			(end -0.120659 -0.279286)
			(stroke
				(width 0.1)
				(type default)
			)
			(layer "F.Fab")
		)
		(fp_line
			(start -0.120617 0.304914)
			(end -0.679417 0.304678)
			(stroke
				(width 0.1)
				(type default)
			)
			(layer "F.Fab")
		)
		(fp_line
			(start -0.120641 0.279514)
			(end -0.120617 0.304914)
			(stroke
				(width 0.1)
				(type default)
			)
			(layer "F.Fab")
		)
		(fp_line
			(start -0.679484 -0.305176)
			(end -0.120683 -0.30494)
			(stroke
				(width 0.1)
				(type default)
			)
			(layer "F.Fab")
		)
		(fp_line
			(start -0.679417 0.304678)
			(end -0.679484 -0.305176)
			(stroke
				(width 0.1)
				(type default)
			)
			(layer "F.Fab")
		)
		(pad "1" smd circle
			(at -0.40005 0 179.946)
			(size 0 0)
			(layers "F.Cu" "F.Mask" "F.Paste")
			(net "PVDD18_S5_P1_FB")
		)
		(pad "2" smd circle
			(at 0.40005 0 179.946)
			(size 0 0)
			(layers "F.Cu" "F.Mask" "F.Paste")
			(net "PVDD18_SS_P1_RGND")
		)
	)
)
